FILE_TYPE = CONNECTIVITY;
{Allegro Design Entry HDL 17.2-2016 S081 (4005846) 1/11/2022}
"PAGE_NUMBER" = 51;
0"NC";
1"M_A_CPU1_SA_CA<6:0>";
2"M_A_CPU1_SA_CS_N<3:0>";
3"M_A_CPU1_SA_DQS_DN<9:0>";
4"M_A_CPU1_SA_DQS_DP<9:0>";
5"M_A_CPU1_SB_CA<6:0>";
6"M_A_CPU1_SB_CS_N<3:0>";
7"M_A_CPU1_SB_DQS_DN<9:0>";
8"M_A_CPU1_SB_DQS_DP<9:0>";
9"M_A_CPU1_SB_CB<7:0>";
10"M_A_CPU1_SB_DQ<31:0>";
11"M_A_CPU1_SA_CB<7:0>";
12"M_A_CPU1_SA_DQ<31:0>";
13"M_A_CPU1_CLK_DP<1:0>";
14"M_A_CPU1_CLK_DN<1:0>";
15"M_A_CPU1_SA_DQ<27>";
16"M_A_CPU1_SA_DQ<26>";
17"M_A_CPU1_SA_DQ<25>";
18"M_A_CPU1_SA_DQ<24>";
19"M_A_CPU1_SA_DQ<23>";
20"M_A_CPU1_SA_DQ<22>";
21"M_A_CPU1_CLK_DN<1>";
22"M_A_CPU1_CLK_DN<0>";
23"M_A_CPU1_CLK_DP<1>";
24"M_A_CPU1_CLK_DP<0>";
25"M_A_CPU1_SA_DQ<31>";
26"M_A_CPU1_SA_DQ<30>";
27"M_A_CPU1_SA_DQ<29>";
28"M_A_CPU1_SA_DQ<28>";
29"M_A_CPU1_SA_DQ<21>";
30"M_A_CPU1_SA_DQ<20>";
31"M_A_CPU1_SA_DQ<19>";
32"M_A_CPU1_SA_DQ<18>";
33"M_A_CPU1_SA_DQ<17>";
34"M_A_CPU1_SA_DQ<16>";
35"M_A_CPU1_SA_DQ<15>";
36"M_A_CPU1_SA_DQ<14>";
37"M_A_CPU1_SA_DQ<13>";
38"M_A_CPU1_SA_DQ<12>";
39"M_A_CPU1_SA_DQ<11>";
40"M_A_CPU1_SA_DQ<10>";
41"M_A_CPU1_SA_DQ<9>";
42"M_A_CPU1_SA_DQ<8>";
43"M_A_CPU1_SA_DQ<7>";
44"M_A_CPU1_SA_DQ<6>";
45"M_A_CPU1_SA_DQ<5>";
46"M_A_CPU1_SA_DQ<4>";
47"M_A_CPU1_SA_DQ<3>";
48"M_A_CPU1_SA_DQ<2>";
49"M_A_CPU1_SA_DQ<1>";
50"M_A_CPU1_SA_DQ<0>";
51"M_A_CPU1_SA_CB<7>";
52"M_A_CPU1_SA_CB<6>";
53"M_A_CPU1_SA_CB<5>";
54"M_A_CPU1_SA_CB<4>";
55"M_A_CPU1_SA_CB<3>";
56"M_A_CPU1_SA_CB<2>";
57"M_A_CPU1_SA_CB<1>";
58"M_A_CPU1_SA_CB<0>";
59"M_A_CPU1_SB_DQ<31>";
60"M_A_CPU1_SB_DQ<30>";
61"M_A_CPU1_SB_DQ<29>";
62"M_A_CPU1_SB_DQ<28>";
63"M_A_CPU1_SB_DQ<27>";
64"M_A_CPU1_SB_DQ<26>";
65"M_A_CPU1_SB_DQ<25>";
66"M_A_CPU1_SB_DQ<24>";
67"M_A_CPU1_SB_DQ<23>";
68"M_A_CPU1_SB_DQ<22>";
69"M_A_CPU1_SB_DQ<21>";
70"M_A_CPU1_SB_DQ<20>";
71"M_A_CPU1_SB_DQ<19>";
72"M_A_CPU1_SB_DQ<18>";
73"M_A_CPU1_SB_DQ<17>";
74"M_A_CPU1_SB_DQ<16>";
75"M_A_CPU1_SB_DQ<15>";
76"M_A_CPU1_SB_DQ<14>";
77"M_A_CPU1_SB_DQ<13>";
78"M_A_CPU1_SB_DQ<12>";
79"M_A_CPU1_SB_DQ<11>";
80"M_A_CPU1_SB_DQ<10>";
81"M_A_CPU1_SB_DQ<9>";
82"M_A_CPU1_SB_DQ<8>";
83"M_A_CPU1_SB_DQ<7>";
84"M_A_CPU1_SB_DQ<6>";
85"M_A_CPU1_SB_DQ<5>";
86"M_A_CPU1_SB_DQ<4>";
87"M_A_CPU1_SB_DQ<3>";
88"M_A_CPU1_SB_DQ<2>";
89"M_A_CPU1_SB_DQ<1>";
90"M_A_CPU1_SB_DQ<0>";
91"M_A_CPU1_SB_CB<7>";
92"M_A_CPU1_SB_CB<6>";
93"M_A_CPU1_SB_CB<5>";
94"M_A_CPU1_SB_CB<4>";
95"M_A_CPU1_SB_CB<3>";
96"M_A_CPU1_SB_CB<2>";
97"M_A_CPU1_SB_CB<1>";
98"M_A_CPU1_SB_CB<0>";
99"M_A_CPU1_SB_PAR";
100"M_A_CPU1_SB_DQS_DP<0>";
101"M_A_CPU1_SB_DQS_DP<1>";
102"M_A_CPU1_SB_DQS_DP<2>";
103"M_A_CPU1_SB_DQS_DP<3>";
104"M_A_CPU1_SB_DQS_DP<4>";
105"M_A_CPU1_SB_DQS_DP<5>";
106"M_A_CPU1_SB_DQS_DP<6>";
107"M_A_CPU1_SB_DQS_DP<7>";
108"M_A_CPU1_SB_DQS_DP<8>";
109"M_A_CPU1_SB_DQS_DP<9>";
110"M_A_CPU1_SB_DQS_DN<0>";
111"M_A_CPU1_SB_DQS_DN<1>";
112"M_A_CPU1_SB_DQS_DN<2>";
113"M_A_CPU1_SB_DQS_DN<3>";
114"M_A_CPU1_SB_DQS_DN<4>";
115"M_A_CPU1_SB_DQS_DN<5>";
116"M_A_CPU1_SB_DQS_DN<6>";
117"M_A_CPU1_SB_DQS_DN<7>";
118"M_A_CPU1_SB_DQS_DN<8>";
119"M_A_CPU1_SB_DQS_DN<9>";
120"M_A_CPU1_SB_CS_N<0>";
121"M_A_CPU1_SB_CS_N<1>";
122"M_A_CPU1_SB_CS_N<2>";
123"M_A_CPU1_SB_CS_N<3>";
124"M_A_CPU1_SB_CA<0>";
125"M_A_CPU1_SB_CA<1>";
126"M_A_CPU1_SB_CA<2>";
127"M_A_CPU1_SB_CA<3>";
128"M_A_CPU1_SB_CA<4>";
129"M_A_CPU1_SB_CA<5>";
130"M_A_CPU1_SB_CA<6>";
131"M_A_CPU1_SA_PAR";
132"M_A_CPU1_SA_DQS_DP<0>";
133"M_A_CPU1_SA_DQS_DP<1>";
134"M_A_CPU1_SA_DQS_DP<2>";
135"M_A_CPU1_SA_DQS_DP<3>";
136"M_A_CPU1_SA_DQS_DP<4>";
137"M_A_CPU1_SA_DQS_DP<5>";
138"M_A_CPU1_SA_DQS_DP<6>";
139"M_A_CPU1_SA_DQS_DP<7>";
140"M_A_CPU1_SA_DQS_DP<8>";
141"M_A_CPU1_SA_DQS_DP<9>";
142"M_A_CPU1_SA_DQS_DN<0>";
143"M_A_CPU1_SA_DQS_DN<1>";
144"M_A_CPU1_SA_DQS_DN<2>";
145"M_A_CPU1_SA_DQS_DN<3>";
146"M_A_CPU1_SA_DQS_DN<4>";
147"M_A_CPU1_SA_DQS_DN<5>";
148"M_A_CPU1_SA_DQS_DN<6>";
149"M_A_CPU1_SA_DQS_DN<7>";
150"M_A_CPU1_SA_DQS_DN<8>";
151"M_A_CPU1_SA_DQS_DN<9>";
152"M_A_CPU1_SA_CS_N<0>";
153"M_A_CPU1_SA_CS_N<1>";
154"M_A_CPU1_SA_CS_N<2>";
155"M_A_CPU1_SA_CS_N<3>";
156"M_A_CPU1_SA_CA<0>";
157"M_A_CPU1_SA_CA<1>";
158"M_A_CPU1_SA_CA<2>";
159"M_A_CPU1_SA_CA<3>";
160"M_A_CPU1_SA_CA<4>";
161"M_A_CPU1_SA_CA<5>";
162"M_A_CPU1_SA_CA<6>";
163"M_A_CPU1_SB_RSP<0>";
164"M_A_CPU1_SB_RSP<1>";
165"M_A_CPU1_SA_RSP<0>";
166"M_A_CPU1_SA_RSP<1>";
167"M_A_CPU1_ALERT_N";
%"TAP"
"1","(-1100,50)","2","standard","I1";
;
CDS_LIB"standard"
BODY_TYPE"PLUMBING"
HDL_TAP"TRUE";
"B \NAC \NWC"14;
"S \NAC"
BN"0"22;
%"TAP"
"1","(-1100,350)","2","standard","I10";
;
CDS_LIB"standard"
BODY_TYPE"PLUMBING"
HDL_TAP"TRUE";
"B \NAC \NWC"9;
"S \NAC"
BN"1"97;
%"TAP"
"1","(2325,950)","0","standard","I100";
;
CDS_LIB"standard"
BODY_TYPE"PLUMBING"
HDL_TAP"TRUE";
"B \NAC \NWC"2;
"S \NAC"
BN"3"155;
%"TAP"
"1","(2325,1150)","0","standard","I101";
;
CDS_LIB"standard"
BODY_TYPE"PLUMBING"
HDL_TAP"TRUE";
"B \NAC \NWC"5;
"S \NAC"
BN"0"124;
%"TAP"
"1","(2325,1200)","0","standard","I102";
;
CDS_LIB"standard"
BODY_TYPE"PLUMBING"
HDL_TAP"TRUE";
"B \NAC \NWC"5;
"S \NAC"
BN"1"125;
%"TAP"
"1","(2325,1300)","0","standard","I103";
;
CDS_LIB"standard"
BODY_TYPE"PLUMBING"
HDL_TAP"TRUE";
"B \NAC \NWC"5;
"S \NAC"
BN"3"127;
%"TAP"
"1","(2325,1250)","0","standard","I104";
;
CDS_LIB"standard"
BODY_TYPE"PLUMBING"
HDL_TAP"TRUE";
"B \NAC \NWC"5;
"S \NAC"
BN"2"126;
%"TAP"
"1","(2325,1400)","0","standard","I105";
;
CDS_LIB"standard"
BODY_TYPE"PLUMBING"
HDL_TAP"TRUE";
"B \NAC \NWC"5;
"S \NAC"
BN"5"129;
%"TAP"
"1","(2325,1450)","0","standard","I106";
;
CDS_LIB"standard"
BODY_TYPE"PLUMBING"
HDL_TAP"TRUE";
"B \NAC \NWC"5;
"S \NAC"
BN"6"130;
%"TAP"
"1","(2325,1350)","0","standard","I107";
;
CDS_LIB"standard"
BODY_TYPE"PLUMBING"
HDL_TAP"TRUE";
"B \NAC \NWC"5;
"S \NAC"
BN"4"128;
%"TAP"
"1","(2325,1650)","0","standard","I108";
;
CDS_LIB"standard"
BODY_TYPE"PLUMBING"
HDL_TAP"TRUE";
"B \NAC \NWC"1;
"S \NAC"
BN"0"156;
%"TAP"
"1","(2325,1700)","0","standard","I109";
;
CDS_LIB"standard"
BODY_TYPE"PLUMBING"
HDL_TAP"TRUE";
"B \NAC \NWC"1;
"S \NAC"
BN"1"157;
%"TAP"
"1","(-1100,400)","2","standard","I11";
;
CDS_LIB"standard"
BODY_TYPE"PLUMBING"
HDL_TAP"TRUE";
"B \NAC \NWC"9;
"S \NAC"
BN"2"96;
%"TAP"
"1","(2325,1750)","0","standard","I110";
;
CDS_LIB"standard"
BODY_TYPE"PLUMBING"
HDL_TAP"TRUE";
"B \NAC \NWC"1;
"S \NAC"
BN"2"158;
%"TAP"
"1","(2325,1800)","0","standard","I111";
;
CDS_LIB"standard"
BODY_TYPE"PLUMBING"
HDL_TAP"TRUE";
"B \NAC \NWC"1;
"S \NAC"
BN"3"159;
%"TAP"
"1","(2325,1950)","0","standard","I112";
;
CDS_LIB"standard"
BODY_TYPE"PLUMBING"
HDL_TAP"TRUE";
"B \NAC \NWC"1;
"S \NAC"
BN"6"162;
%"TAP"
"1","(2325,1850)","0","standard","I113";
;
CDS_LIB"standard"
BODY_TYPE"PLUMBING"
HDL_TAP"TRUE";
"B \NAC \NWC"1;
"S \NAC"
BN"4"160;
%"TAP"
"1","(2325,1900)","0","standard","I114";
;
CDS_LIB"standard"
BODY_TYPE"PLUMBING"
HDL_TAP"TRUE";
"B \NAC \NWC"1;
"S \NAC"
BN"5"161;
%"TAP"
"1","(-1100,500)","2","standard","I12";
;
CDS_LIB"standard"
BODY_TYPE"PLUMBING"
HDL_TAP"TRUE";
"B \NAC \NWC"9;
"S \NAC"
BN"4"94;
%"TAP"
"1","(2325,2100)","0","standard","I125";
;
CDS_LIB"standard"
BODY_TYPE"PLUMBING"
HDL_TAP"TRUE";
"B \NAC \NWC"7;
"S \NAC"
BN"0"110;
%"TAP"
"1","(2325,2200)","0","standard","I126";
;
CDS_LIB"standard"
BODY_TYPE"PLUMBING"
HDL_TAP"TRUE";
"B \NAC \NWC"7;
"S \NAC"
BN"2"112;
%"TAP"
"1","(2325,2150)","0","standard","I127";
;
CDS_LIB"standard"
BODY_TYPE"PLUMBING"
HDL_TAP"TRUE";
"B \NAC \NWC"7;
"S \NAC"
BN"1"111;
%"TAP"
"1","(2325,2250)","0","standard","I128";
;
CDS_LIB"standard"
BODY_TYPE"PLUMBING"
HDL_TAP"TRUE";
"B \NAC \NWC"7;
"S \NAC"
BN"3"113;
%"TAP"
"1","(2325,2300)","0","standard","I129";
;
CDS_LIB"standard"
BODY_TYPE"PLUMBING"
HDL_TAP"TRUE";
"B \NAC \NWC"7;
"S \NAC"
BN"4"114;
%"TAP"
"1","(-1100,450)","2","standard","I13";
;
CDS_LIB"standard"
BODY_TYPE"PLUMBING"
HDL_TAP"TRUE";
"B \NAC \NWC"9;
"S \NAC"
BN"3"95;
%"TAP"
"1","(2325,2350)","0","standard","I130";
;
CDS_LIB"standard"
BODY_TYPE"PLUMBING"
HDL_TAP"TRUE";
"B \NAC \NWC"7;
"S \NAC"
BN"5"115;
%"TAP"
"1","(2325,2400)","0","standard","I131";
;
CDS_LIB"standard"
BODY_TYPE"PLUMBING"
HDL_TAP"TRUE";
"B \NAC \NWC"7;
"S \NAC"
BN"6"116;
%"TAP"
"1","(2325,2450)","0","standard","I132";
;
CDS_LIB"standard"
BODY_TYPE"PLUMBING"
HDL_TAP"TRUE";
"B \NAC \NWC"7;
"S \NAC"
BN"7"117;
%"TAP"
"1","(2325,2500)","0","standard","I133";
;
CDS_LIB"standard"
BODY_TYPE"PLUMBING"
HDL_TAP"TRUE";
"B \NAC \NWC"7;
"S \NAC"
BN"8"118;
%"TAP"
"1","(2325,2550)","0","standard","I134";
;
CDS_LIB"standard"
BODY_TYPE"PLUMBING"
HDL_TAP"TRUE";
"B \NAC \NWC"7;
"S \NAC"
BN"9"119;
%"TAP"
"1","(2325,2650)","0","standard","I135";
;
CDS_LIB"standard"
BODY_TYPE"PLUMBING"
HDL_TAP"TRUE";
"B \NAC \NWC"8;
"S \NAC"
BN"0"100;
%"TAP"
"1","(2325,2700)","0","standard","I136";
;
CDS_LIB"standard"
BODY_TYPE"PLUMBING"
HDL_TAP"TRUE";
"B \NAC \NWC"8;
"S \NAC"
BN"1"101;
%"TAP"
"1","(2325,2850)","0","standard","I137";
;
CDS_LIB"standard"
BODY_TYPE"PLUMBING"
HDL_TAP"TRUE";
"B \NAC \NWC"8;
"S \NAC"
BN"4"104;
%"TAP"
"1","(2325,2750)","0","standard","I138";
;
CDS_LIB"standard"
BODY_TYPE"PLUMBING"
HDL_TAP"TRUE";
"B \NAC \NWC"8;
"S \NAC"
BN"2"102;
%"TAP"
"1","(2325,2800)","0","standard","I139";
;
CDS_LIB"standard"
BODY_TYPE"PLUMBING"
HDL_TAP"TRUE";
"B \NAC \NWC"8;
"S \NAC"
BN"3"103;
%"TAP"
"1","(-1100,550)","2","standard","I14";
;
CDS_LIB"standard"
BODY_TYPE"PLUMBING"
HDL_TAP"TRUE";
"B \NAC \NWC"9;
"S \NAC"
BN"5"93;
%"TAP"
"1","(2325,2900)","0","standard","I140";
;
CDS_LIB"standard"
BODY_TYPE"PLUMBING"
HDL_TAP"TRUE";
"B \NAC \NWC"8;
"S \NAC"
BN"5"105;
%"TAP"
"1","(2325,2950)","0","standard","I141";
;
CDS_LIB"standard"
BODY_TYPE"PLUMBING"
HDL_TAP"TRUE";
"B \NAC \NWC"8;
"S \NAC"
BN"6"106;
%"TAP"
"1","(2325,3100)","0","standard","I142";
;
CDS_LIB"standard"
BODY_TYPE"PLUMBING"
HDL_TAP"TRUE";
"B \NAC \NWC"8;
"S \NAC"
BN"9"109;
%"TAP"
"1","(2325,3050)","0","standard","I143";
;
CDS_LIB"standard"
BODY_TYPE"PLUMBING"
HDL_TAP"TRUE";
"B \NAC \NWC"8;
"S \NAC"
BN"8"108;
%"TAP"
"1","(2325,3000)","0","standard","I144";
;
CDS_LIB"standard"
BODY_TYPE"PLUMBING"
HDL_TAP"TRUE";
"B \NAC \NWC"8;
"S \NAC"
BN"7"107;
%"TAP"
"1","(2325,3250)","0","standard","I145";
;
CDS_LIB"standard"
BODY_TYPE"PLUMBING"
HDL_TAP"TRUE";
"B \NAC \NWC"3;
"S \NAC"
BN"0"142;
%"TAP"
"1","(2325,3350)","0","standard","I146";
;
CDS_LIB"standard"
BODY_TYPE"PLUMBING"
HDL_TAP"TRUE";
"B \NAC \NWC"3;
"S \NAC"
BN"2"144;
%"TAP"
"1","(2325,3300)","0","standard","I147";
;
CDS_LIB"standard"
BODY_TYPE"PLUMBING"
HDL_TAP"TRUE";
"B \NAC \NWC"3;
"S \NAC"
BN"1"143;
%"TAP"
"1","(2325,3400)","0","standard","I148";
;
CDS_LIB"standard"
BODY_TYPE"PLUMBING"
HDL_TAP"TRUE";
"B \NAC \NWC"3;
"S \NAC"
BN"3"145;
%"TAP"
"1","(2325,3500)","0","standard","I149";
;
CDS_LIB"standard"
BODY_TYPE"PLUMBING"
HDL_TAP"TRUE";
"B \NAC \NWC"3;
"S \NAC"
BN"5"147;
%"TAP"
"1","(-1100,600)","2","standard","I15";
;
CDS_LIB"standard"
BODY_TYPE"PLUMBING"
HDL_TAP"TRUE";
"B \NAC \NWC"9;
"S \NAC"
BN"6"92;
%"TAP"
"1","(2325,3450)","0","standard","I150";
;
CDS_LIB"standard"
BODY_TYPE"PLUMBING"
HDL_TAP"TRUE";
"B \NAC \NWC"3;
"S \NAC"
BN"4"146;
%"TAP"
"1","(2325,3600)","0","standard","I151";
;
CDS_LIB"standard"
BODY_TYPE"PLUMBING"
HDL_TAP"TRUE";
"B \NAC \NWC"3;
"S \NAC"
BN"7"149;
%"TAP"
"1","(2325,3550)","0","standard","I152";
;
CDS_LIB"standard"
BODY_TYPE"PLUMBING"
HDL_TAP"TRUE";
"B \NAC \NWC"3;
"S \NAC"
BN"6"148;
%"TAP"
"1","(2325,3700)","0","standard","I153";
;
CDS_LIB"standard"
BODY_TYPE"PLUMBING"
HDL_TAP"TRUE";
"B \NAC \NWC"3;
"S \NAC"
BN"9"151;
%"TAP"
"1","(2325,3650)","0","standard","I154";
;
CDS_LIB"standard"
BODY_TYPE"PLUMBING"
HDL_TAP"TRUE";
"B \NAC \NWC"3;
"S \NAC"
BN"8"150;
%"TAP"
"1","(2325,3850)","0","standard","I155";
;
CDS_LIB"standard"
BODY_TYPE"PLUMBING"
HDL_TAP"TRUE";
"B \NAC \NWC"4;
"S \NAC"
BN"1"133;
%"TAP"
"1","(2325,3800)","0","standard","I156";
;
CDS_LIB"standard"
BODY_TYPE"PLUMBING"
HDL_TAP"TRUE";
"B \NAC \NWC"4;
"S \NAC"
BN"0"132;
%"TAP"
"1","(2325,3900)","0","standard","I157";
;
CDS_LIB"standard"
BODY_TYPE"PLUMBING"
HDL_TAP"TRUE";
"B \NAC \NWC"4;
"S \NAC"
BN"2"134;
%"TAP"
"1","(2325,3950)","0","standard","I158";
;
CDS_LIB"standard"
BODY_TYPE"PLUMBING"
HDL_TAP"TRUE";
"B \NAC \NWC"4;
"S \NAC"
BN"3"135;
%"TAP"
"1","(2325,4000)","0","standard","I159";
;
CDS_LIB"standard"
BODY_TYPE"PLUMBING"
HDL_TAP"TRUE";
"B \NAC \NWC"4;
"S \NAC"
BN"4"136;
%"TAP"
"1","(-1100,650)","2","standard","I16";
;
CDS_LIB"standard"
BODY_TYPE"PLUMBING"
HDL_TAP"TRUE";
"B \NAC \NWC"9;
"S \NAC"
BN"7"91;
%"TAP"
"1","(2325,4050)","0","standard","I160";
;
CDS_LIB"standard"
BODY_TYPE"PLUMBING"
HDL_TAP"TRUE";
"B \NAC \NWC"4;
"S \NAC"
BN"5"137;
%"TAP"
"1","(2325,4100)","0","standard","I161";
;
CDS_LIB"standard"
BODY_TYPE"PLUMBING"
HDL_TAP"TRUE";
"B \NAC \NWC"4;
"S \NAC"
BN"6"138;
%"TAP"
"1","(2325,4250)","0","standard","I165";
;
CDS_LIB"standard"
BODY_TYPE"PLUMBING"
HDL_TAP"TRUE";
"B \NAC \NWC"4;
"S \NAC"
BN"9"141;
%"TAP"
"1","(2325,4200)","0","standard","I166";
;
CDS_LIB"standard"
BODY_TYPE"PLUMBING"
HDL_TAP"TRUE";
"B \NAC \NWC"4;
"S \NAC"
BN"8"140;
%"TAP"
"1","(2325,4150)","0","standard","I167";
;
CDS_LIB"standard"
BODY_TYPE"PLUMBING"
HDL_TAP"TRUE";
"B \NAC \NWC"4;
"S \NAC"
BN"7"139;
%"TAP"
"1","(-1100,750)","2","standard","I17";
;
CDS_LIB"standard"
BODY_TYPE"PLUMBING"
HDL_TAP"TRUE";
"B \NAC \NWC"10;
"S \NAC"
BN"1"89;
%"TAP"
"1","(-1100,700)","2","standard","I18";
;
CDS_LIB"standard"
BODY_TYPE"PLUMBING"
HDL_TAP"TRUE";
"B \NAC \NWC"10;
"S \NAC"
BN"0"90;
%"TAP"
"1","(-1100,800)","2","standard","I19";
;
CDS_LIB"standard"
BODY_TYPE"PLUMBING"
HDL_TAP"TRUE";
"B \NAC \NWC"10;
"S \NAC"
BN"2"88;
%"SOCKET4677_AZIF0045P001C01CS"
"8","(625,2150)","0","pure_quanta","I2";
;
PART_NUMBER"DGA^7000023"
PART_TYPE"SMLF"
MATERIAL"IO"
VALUE"SOCKET4677_AZIF0045-P001C01CS"
$LOCATION"U1"
CDS_LIB"pure_quanta"
NEEDS_NO_SIZE"TRUE"
CDS_LMAN_SYM_OUTLINE"-1100,2250,1050,-2250"
CDS_LOCATION"U1"
$SEC"8"
CDS_SEC"8";
"DDR0_SB_PAR"
$PN"G39"99;
"DDR0_SB_ECC0"
$PN"B32"98;
"DDR0_SB_ECC1"
$PN"C31"97;
"DDR0_SB_ECC2"
$PN"F32"96;
"DDR0_SB_ECC3"
$PN"E31"95;
"DDR0_SB_ECC4"
$PN"C35"94;
"DDR0_SB_ECC5"
$PN"B34"93;
"DDR0_SB_ECC6"
$PN"E35"92;
"DDR0_SB_ECC7"
$PN"F34"91;
"DDR0_SB_DQS_DP0"
$PN"K30"100;
"DDR0_SB_DQS_DP1"
$PN"C27"101;
"DDR0_SB_DQS_DP2"
$PN"C21"102;
"DDR0_SB_DQS_DP3"
$PN"C9"103;
"DDR0_SB_DQS_DP4"
$PN"E33"104;
"DDR0_SB_DQS_DP5"
$PN"P30"105;
"DDR0_SB_DQS_DP6"
$PN"E27"106;
"DDR0_SB_DQS_DP7"
$PN"E21"107;
"DDR0_SB_DQS_DP8"
$PN"E9"108;
"DDR0_SB_DQS_DP9"
$PN"C33"109;
"DDR0_SB_DQS_DN0 \B"
$PN"H30"110;
"DDR0_SB_DQS_DN1 \B"
$PN"A27"111;
"DDR0_SB_DQS_DN2 \B"
$PN"A21"112;
"DDR0_SB_DQS_DN3 \B"
$PN"A9"113;
"DDR0_SB_DQS_DN4 \B"
$PN"G33"114;
"DDR0_SB_DQS_DN5 \B"
$PN"M30"115;
"DDR0_SB_DQS_DN6 \B"
$PN"G27"116;
"DDR0_SB_DQS_DN7 \B"
$PN"G21"117;
"DDR0_SB_DQS_DN8 \B"
$PN"G9"118;
"DDR0_SB_DQS_DN9 \B"
$PN"A33"119;
"DDR0_SB_DQ0"
$PN"K32"90;
"DDR0_SB_DQ1"
$PN"J31"89;
"DDR0_SB_DQ2"
$PN"M32"88;
"DDR0_SB_DQ3"
$PN"N31"87;
"DDR0_SB_DQ4"
$PN"J29"86;
"DDR0_SB_DQ5"
$PN"K28"85;
"DDR0_SB_DQ6"
$PN"N29"84;
"DDR0_SB_DQ7"
$PN"M28"83;
"DDR0_SB_DQ8"
$PN"C29"82;
"DDR0_SB_DQ9"
$PN"B28"81;
"DDR0_SB_DQ10"
$PN"E29"80;
"DDR0_SB_DQ11"
$PN"F28"79;
"DDR0_SB_DQ12"
$PN"B26"78;
"DDR0_SB_DQ13"
$PN"C25"77;
"DDR0_SB_DQ14"
$PN"F26"76;
"DDR0_SB_DQ15"
$PN"E25"75;
"DDR0_SB_DQ16"
$PN"C23"74;
"DDR0_SB_DQ17"
$PN"B22"73;
"DDR0_SB_DQ18"
$PN"E23"72;
"DDR0_SB_DQ19"
$PN"F22"71;
"DDR0_SB_DQ20"
$PN"B20"70;
"DDR0_SB_DQ21"
$PN"C19"69;
"DDR0_SB_DQ22"
$PN"F20"68;
"DDR0_SB_DQ23"
$PN"E19"67;
"DDR0_SB_DQ24"
$PN"C11"66;
"DDR0_SB_DQ25"
$PN"B10"65;
"DDR0_SB_DQ26"
$PN"E11"64;
"DDR0_SB_DQ27"
$PN"F10"63;
"DDR0_SB_DQ28"
$PN"B8"62;
"DDR0_SB_DQ29"
$PN"C7"61;
"DDR0_SB_DQ30"
$PN"F8"60;
"DDR0_SB_DQ31"
$PN"E7"59;
"DDR0_SB_CS_N0 \B"
$PN"B38"120;
"DDR0_SB_CS_N1 \B"
$PN"C37"121;
"DDR0_SB_CS_N2 \B"
$PN"F38"122;
"DDR0_SB_CS_N3 \B"
$PN"E37"123;
"DDR0_SB_CA0"
$PN"E43"124;
"DDR0_SB_CA1"
$PN"F44"125;
"DDR0_SB_CA2"
$PN"C41"126;
"DDR0_SB_CA3"
$PN"E41"127;
"DDR0_SB_CA4"
$PN"B40"128;
"DDR0_SB_CA5"
$PN"F40"129;
"DDR0_SB_CA6"
$PN"A39"130;
"DDR0_SA_PAR"
$PN"E48"131;
"DDR0_SA_ECC0"
$PN"C60"58;
"DDR0_SA_ECC1"
$PN"B59"57;
"DDR0_SA_ECC2"
$PN"E60"56;
"DDR0_SA_ECC3"
$PN"F59"55;
"DDR0_SA_ECC4"
$PN"B57"54;
"DDR0_SA_ECC5"
$PN"C56"53;
"DDR0_SA_ECC6"
$PN"F57"52;
"DDR0_SA_ECC7"
$PN"E56"51;
"DDR0_SA_DQS_DP0"
$PN"D77"132;
"DDR0_SA_DQS_DP1"
$PN"K67"133;
"DDR0_SA_DQS_DP2"
$PN"C70"134;
"DDR0_SA_DQS_DP3"
$PN"C64"135;
"DDR0_SA_DQS_DP4"
$PN"C58"136;
"DDR0_SA_DQS_DP5"
$PN"F77"137;
"DDR0_SA_DQS_DP6"
$PN"M67"138;
"DDR0_SA_DQS_DP7"
$PN"E70"139;
"DDR0_SA_DQS_DP8"
$PN"E64"140;
"DDR0_SA_DQS_DP9"
$PN"E58"141;
"DDR0_SA_DQS_DN0 \B"
$PN"B77"142;
"DDR0_SA_DQS_DN1 \B"
$PN"H67"143;
"DDR0_SA_DQS_DN2 \B"
$PN"B71"144;
"DDR0_SA_DQS_DN3 \B"
$PN"A64"145;
"DDR0_SA_DQS_DN4 \B"
$PN"A58"146;
"DDR0_SA_DQS_DN5 \B"
$PN"H77"147;
"DDR0_SA_DQS_DN6 \B"
$PN"P67"148;
"DDR0_SA_DQS_DN7 \B"
$PN"G70"149;
"DDR0_SA_DQS_DN8 \B"
$PN"G64"150;
"DDR0_SA_DQS_DN9 \B"
$PN"G58"151;
"DDR0_SA_DQ0"
$PN"B81"50;
"DDR0_SA_DQ1"
$PN"B79"49;
"DDR0_SA_DQ2"
$PN"M77"48;
"DDR0_SA_DQ3"
$PN"G78"47;
"DDR0_SA_DQ4"
$PN"C76"46;
"DDR0_SA_DQ5"
$PN"D75"45;
"DDR0_SA_DQ6"
$PN"G76"44;
"DDR0_SA_DQ7"
$PN"F75"43;
"DDR0_SA_DQ8"
$PN"K69"42;
"DDR0_SA_DQ9"
$PN"J68"41;
"DDR0_SA_DQ10"
$PN"M69"40;
"DDR0_SA_DQ11"
$PN"N68"39;
"DDR0_SA_DQ12"
$PN"J66"38;
"DDR0_SA_DQ13"
$PN"K65"37;
"DDR0_SA_DQ14"
$PN"N66"36;
"DDR0_SA_DQ15"
$PN"M65"35;
"DDR0_SA_DQ16"
$PN"B73"34;
"DDR0_SA_DQ17"
$PN"E72"33;
"DDR0_SA_DQ18"
$PN"D73"32;
"DDR0_SA_DQ19"
$PN"F71"31;
"DDR0_SA_DQ20"
$PN"B69"30;
"DDR0_SA_DQ21"
$PN"C68"29;
"DDR0_SA_DQ22"
$PN"F69"20;
"DDR0_SA_DQ23"
$PN"E68"19;
"DDR0_SA_DQ24"
$PN"C66"18;
"DDR0_SA_DQ25"
$PN"B65"17;
"DDR0_SA_DQ26"
$PN"E66"16;
"DDR0_SA_DQ27"
$PN"F65"15;
"DDR0_SA_DQ28"
$PN"B63"28;
"DDR0_SA_DQ29"
$PN"C62"27;
"DDR0_SA_DQ30"
$PN"F63"26;
"DDR0_SA_DQ31"
$PN"E62"25;
"DDR0_SA_CS_N0 \B"
$PN"C54"152;
"DDR0_SA_CS_N1 \B"
$PN"B53"153;
"DDR0_SA_CS_N2 \B"
$PN"E54"154;
"DDR0_SA_CS_N3 \B"
$PN"F53"155;
"DDR0_SA_CA0"
$PN"A52"156;
"DDR0_SA_CA1"
$PN"G52"157;
"DDR0_SA_CA2"
$PN"B51"158;
"DDR0_SA_CA3"
$PN"F51"159;
"DDR0_SA_CA4"
$PN"C50"160;
"DDR0_SA_CA5"
$PN"E50"161;
"DDR0_SA_CA6"
$PN"C48"162;
"DDR0_CLK_DP0"
$PN"C43"24;
"DDR0_CLK_DP1"
$PN"E45"23;
"DDR0_CLK_DN0 \B"
$PN"B44"22;
"DDR0_CLK_DN1 \B"
$PN"G45"21;
"DDR0_B_RSP0"
$PN"AV44"163;
"DDR0_B_RSP1"
$PN"AV42"164;
"DDR0_A_RSP0"
$PN"AT42"165;
"DDR0_A_RSP1"
$PN"AU43"166;
"DDR0_ALERT_N \B"
$PN"AT49"167;
%"TAP"
"1","(-1100,850)","2","standard","I20";
;
CDS_LIB"standard"
BODY_TYPE"PLUMBING"
HDL_TAP"TRUE";
"B \NAC \NWC"10;
"S \NAC"
BN"3"87;
%"TAP"
"1","(-1100,900)","2","standard","I21";
;
CDS_LIB"standard"
BODY_TYPE"PLUMBING"
HDL_TAP"TRUE";
"B \NAC \NWC"10;
"S \NAC"
BN"4"86;
%"TAP"
"1","(-1100,1000)","2","standard","I22";
;
CDS_LIB"standard"
BODY_TYPE"PLUMBING"
HDL_TAP"TRUE";
"B \NAC \NWC"10;
"S \NAC"
BN"6"84;
%"TAP"
"1","(-1100,950)","2","standard","I23";
;
CDS_LIB"standard"
BODY_TYPE"PLUMBING"
HDL_TAP"TRUE";
"B \NAC \NWC"10;
"S \NAC"
BN"5"85;
%"TAP"
"1","(-1100,1050)","2","standard","I24";
;
CDS_LIB"standard"
BODY_TYPE"PLUMBING"
HDL_TAP"TRUE";
"B \NAC \NWC"10;
"S \NAC"
BN"7"83;
%"TAP"
"1","(-1100,1150)","2","standard","I25";
;
CDS_LIB"standard"
BODY_TYPE"PLUMBING"
HDL_TAP"TRUE";
"B \NAC \NWC"10;
"S \NAC"
BN"9"81;
%"TAP"
"1","(-1100,1100)","2","standard","I26";
;
CDS_LIB"standard"
BODY_TYPE"PLUMBING"
HDL_TAP"TRUE";
"B \NAC \NWC"10;
"S \NAC"
BN"8"82;
%"TAP"
"1","(-1100,1300)","2","standard","I27";
;
CDS_LIB"standard"
BODY_TYPE"PLUMBING"
HDL_TAP"TRUE";
"B \NAC \NWC"10;
"S \NAC"
BN"12"78;
%"TAP"
"1","(-1100,1250)","2","standard","I28";
;
CDS_LIB"standard"
BODY_TYPE"PLUMBING"
HDL_TAP"TRUE";
"B \NAC \NWC"10;
"S \NAC"
BN"11"79;
%"TAP"
"1","(-1100,1200)","2","standard","I29";
;
CDS_LIB"standard"
BODY_TYPE"PLUMBING"
HDL_TAP"TRUE";
"B \NAC \NWC"10;
"S \NAC"
BN"10"80;
%"TAP"
"1","(-1100,1350)","2","standard","I30";
;
CDS_LIB"standard"
BODY_TYPE"PLUMBING"
HDL_TAP"TRUE";
"B \NAC \NWC"10;
"S \NAC"
BN"13"77;
%"TAP"
"1","(-1100,1400)","2","standard","I31";
;
CDS_LIB"standard"
BODY_TYPE"PLUMBING"
HDL_TAP"TRUE";
"B \NAC \NWC"10;
"S \NAC"
BN"14"76;
%"TAP"
"1","(-1100,1500)","2","standard","I32";
;
CDS_LIB"standard"
BODY_TYPE"PLUMBING"
HDL_TAP"TRUE";
"B \NAC \NWC"10;
"S \NAC"
BN"16"74;
%"TAP"
"1","(-1100,1550)","2","standard","I33";
;
CDS_LIB"standard"
BODY_TYPE"PLUMBING"
HDL_TAP"TRUE";
"B \NAC \NWC"10;
"S \NAC"
BN"17"73;
%"TAP"
"1","(-1100,1450)","2","standard","I34";
;
CDS_LIB"standard"
BODY_TYPE"PLUMBING"
HDL_TAP"TRUE";
"B \NAC \NWC"10;
"S \NAC"
BN"15"75;
%"TAP"
"1","(-1100,1600)","2","standard","I35";
;
CDS_LIB"standard"
BODY_TYPE"PLUMBING"
HDL_TAP"TRUE";
"B \NAC \NWC"10;
"S \NAC"
BN"18"72;
%"TAP"
"1","(-1100,1650)","2","standard","I36";
;
CDS_LIB"standard"
BODY_TYPE"PLUMBING"
HDL_TAP"TRUE";
"B \NAC \NWC"10;
"S \NAC"
BN"19"71;
%"TAP"
"1","(-1100,1750)","2","standard","I37";
;
CDS_LIB"standard"
BODY_TYPE"PLUMBING"
HDL_TAP"TRUE";
"B \NAC \NWC"10;
"S \NAC"
BN"21"69;
%"TAP"
"1","(-1100,1800)","2","standard","I38";
;
CDS_LIB"standard"
BODY_TYPE"PLUMBING"
HDL_TAP"TRUE";
"B \NAC \NWC"10;
"S \NAC"
BN"22"68;
%"TAP"
"1","(-1100,1700)","2","standard","I39";
;
CDS_LIB"standard"
BODY_TYPE"PLUMBING"
HDL_TAP"TRUE";
"B \NAC \NWC"10;
"S \NAC"
BN"20"70;
%"TAP"
"1","(-1100,1850)","2","standard","I40";
;
CDS_LIB"standard"
BODY_TYPE"PLUMBING"
HDL_TAP"TRUE";
"B \NAC \NWC"10;
"S \NAC"
BN"23"67;
%"TAP"
"1","(-1100,1900)","2","standard","I41";
;
CDS_LIB"standard"
BODY_TYPE"PLUMBING"
HDL_TAP"TRUE";
"B \NAC \NWC"10;
"S \NAC"
BN"24"66;
%"TAP"
"1","(-1100,2000)","2","standard","I42";
;
CDS_LIB"standard"
BODY_TYPE"PLUMBING"
HDL_TAP"TRUE";
"B \NAC \NWC"10;
"S \NAC"
BN"26"64;
%"TAP"
"1","(-1100,2050)","2","standard","I43";
;
CDS_LIB"standard"
BODY_TYPE"PLUMBING"
HDL_TAP"TRUE";
"B \NAC \NWC"10;
"S \NAC"
BN"27"63;
%"TAP"
"1","(-1100,1950)","2","standard","I44";
;
CDS_LIB"standard"
BODY_TYPE"PLUMBING"
HDL_TAP"TRUE";
"B \NAC \NWC"10;
"S \NAC"
BN"25"65;
%"TAP"
"1","(-1100,2200)","2","standard","I47";
;
CDS_LIB"standard"
BODY_TYPE"PLUMBING"
HDL_TAP"TRUE";
"B \NAC \NWC"10;
"S \NAC"
BN"30"60;
%"TAP"
"1","(-1100,2150)","2","standard","I48";
;
CDS_LIB"standard"
BODY_TYPE"PLUMBING"
HDL_TAP"TRUE";
"B \NAC \NWC"10;
"S \NAC"
BN"29"61;
%"TAP"
"1","(-1100,2100)","2","standard","I49";
;
CDS_LIB"standard"
BODY_TYPE"PLUMBING"
HDL_TAP"TRUE";
"B \NAC \NWC"10;
"S \NAC"
BN"28"62;
%"TAP"
"1","(-1100,2250)","2","standard","I50";
;
CDS_LIB"standard"
BODY_TYPE"PLUMBING"
HDL_TAP"TRUE";
"B \NAC \NWC"10;
"S \NAC"
BN"31"59;
%"TAP"
"1","(-1100,2300)","2","standard","I51";
;
CDS_LIB"standard"
BODY_TYPE"PLUMBING"
HDL_TAP"TRUE";
"B \NAC \NWC"11;
"S \NAC"
BN"0"58;
%"TAP"
"1","(-1100,2350)","2","standard","I52";
;
CDS_LIB"standard"
BODY_TYPE"PLUMBING"
HDL_TAP"TRUE";
"B \NAC \NWC"11;
"S \NAC"
BN"1"57;
%"TAP"
"1","(-1100,2400)","2","standard","I53";
;
CDS_LIB"standard"
BODY_TYPE"PLUMBING"
HDL_TAP"TRUE";
"B \NAC \NWC"11;
"S \NAC"
BN"2"56;
%"TAP"
"1","(-1100,2450)","2","standard","I54";
;
CDS_LIB"standard"
BODY_TYPE"PLUMBING"
HDL_TAP"TRUE";
"B \NAC \NWC"11;
"S \NAC"
BN"3"55;
%"TAP"
"1","(-1100,2500)","2","standard","I55";
;
CDS_LIB"standard"
BODY_TYPE"PLUMBING"
HDL_TAP"TRUE";
"B \NAC \NWC"11;
"S \NAC"
BN"4"54;
%"TAP"
"1","(-1100,2550)","2","standard","I56";
;
CDS_LIB"standard"
BODY_TYPE"PLUMBING"
HDL_TAP"TRUE";
"B \NAC \NWC"11;
"S \NAC"
BN"5"53;
%"TAP"
"1","(-1100,2600)","2","standard","I57";
;
CDS_LIB"standard"
BODY_TYPE"PLUMBING"
HDL_TAP"TRUE";
"B \NAC \NWC"11;
"S \NAC"
BN"6"52;
%"TAP"
"1","(-1100,2650)","2","standard","I58";
;
CDS_LIB"standard"
BODY_TYPE"PLUMBING"
HDL_TAP"TRUE";
"B \NAC \NWC"11;
"S \NAC"
BN"7"51;
%"TAP"
"1","(-1100,2700)","2","standard","I59";
;
CDS_LIB"standard"
BODY_TYPE"PLUMBING"
HDL_TAP"TRUE";
"B \NAC \NWC"12;
"S \NAC"
BN"0"50;
%"TAP"
"1","(-1100,200)","2","standard","I6";
;
CDS_LIB"standard"
BODY_TYPE"PLUMBING"
HDL_TAP"TRUE";
"B \NAC \NWC"13;
"S \NAC"
BN"1"23;
%"TAP"
"1","(-1100,2800)","2","standard","I60";
;
CDS_LIB"standard"
BODY_TYPE"PLUMBING"
HDL_TAP"TRUE";
"B \NAC \NWC"12;
"S \NAC"
BN"2"48;
%"TAP"
"1","(-1100,2750)","2","standard","I61";
;
CDS_LIB"standard"
BODY_TYPE"PLUMBING"
HDL_TAP"TRUE";
"B \NAC \NWC"12;
"S \NAC"
BN"1"49;
%"TAP"
"1","(-1100,2850)","2","standard","I62";
;
CDS_LIB"standard"
BODY_TYPE"PLUMBING"
HDL_TAP"TRUE";
"B \NAC \NWC"12;
"S \NAC"
BN"3"47;
%"TAP"
"1","(-1100,2900)","2","standard","I63";
;
CDS_LIB"standard"
BODY_TYPE"PLUMBING"
HDL_TAP"TRUE";
"B \NAC \NWC"12;
"S \NAC"
BN"4"46;
%"TAP"
"1","(-1100,2950)","2","standard","I64";
;
CDS_LIB"standard"
BODY_TYPE"PLUMBING"
HDL_TAP"TRUE";
"B \NAC \NWC"12;
"S \NAC"
BN"5"45;
%"TAP"
"1","(-1100,3050)","2","standard","I65";
;
CDS_LIB"standard"
BODY_TYPE"PLUMBING"
HDL_TAP"TRUE";
"B \NAC \NWC"12;
"S \NAC"
BN"7"43;
%"TAP"
"1","(-1100,3000)","2","standard","I66";
;
CDS_LIB"standard"
BODY_TYPE"PLUMBING"
HDL_TAP"TRUE";
"B \NAC \NWC"12;
"S \NAC"
BN"6"44;
%"TAP"
"1","(-1100,3100)","2","standard","I67";
;
CDS_LIB"standard"
BODY_TYPE"PLUMBING"
HDL_TAP"TRUE";
"B \NAC \NWC"12;
"S \NAC"
BN"8"42;
%"TAP"
"1","(-1100,3150)","2","standard","I68";
;
CDS_LIB"standard"
BODY_TYPE"PLUMBING"
HDL_TAP"TRUE";
"B \NAC \NWC"12;
"S \NAC"
BN"9"41;
%"TAP"
"1","(-1100,3200)","2","standard","I69";
;
CDS_LIB"standard"
BODY_TYPE"PLUMBING"
HDL_TAP"TRUE";
"B \NAC \NWC"12;
"S \NAC"
BN"10"40;
%"TAP"
"1","(-1100,150)","2","standard","I7";
;
CDS_LIB"standard"
BODY_TYPE"PLUMBING"
HDL_TAP"TRUE";
"B \NAC \NWC"13;
"S \NAC"
BN"0"24;
%"TAP"
"1","(-1100,3250)","2","standard","I70";
;
CDS_LIB"standard"
BODY_TYPE"PLUMBING"
HDL_TAP"TRUE";
"B \NAC \NWC"12;
"S \NAC"
BN"11"39;
%"TAP"
"1","(-1100,3350)","2","standard","I71";
;
CDS_LIB"standard"
BODY_TYPE"PLUMBING"
HDL_TAP"TRUE";
"B \NAC \NWC"12;
"S \NAC"
BN"13"37;
%"TAP"
"1","(-1100,3300)","2","standard","I72";
;
CDS_LIB"standard"
BODY_TYPE"PLUMBING"
HDL_TAP"TRUE";
"B \NAC \NWC"12;
"S \NAC"
BN"12"38;
%"TAP"
"1","(-1100,3400)","2","standard","I73";
;
CDS_LIB"standard"
BODY_TYPE"PLUMBING"
HDL_TAP"TRUE";
"B \NAC \NWC"12;
"S \NAC"
BN"14"36;
%"TAP"
"1","(-1100,3450)","2","standard","I74";
;
CDS_LIB"standard"
BODY_TYPE"PLUMBING"
HDL_TAP"TRUE";
"B \NAC \NWC"12;
"S \NAC"
BN"15"35;
%"TAP"
"1","(-1100,3550)","2","standard","I75";
;
CDS_LIB"standard"
BODY_TYPE"PLUMBING"
HDL_TAP"TRUE";
"B \NAC \NWC"12;
"S \NAC"
BN"17"33;
%"TAP"
"1","(-1100,3600)","2","standard","I76";
;
CDS_LIB"standard"
BODY_TYPE"PLUMBING"
HDL_TAP"TRUE";
"B \NAC \NWC"12;
"S \NAC"
BN"18"32;
%"TAP"
"1","(-1100,3500)","2","standard","I77";
;
CDS_LIB"standard"
BODY_TYPE"PLUMBING"
HDL_TAP"TRUE";
"B \NAC \NWC"12;
"S \NAC"
BN"16"34;
%"TAP"
"1","(-1100,3650)","2","standard","I78";
;
CDS_LIB"standard"
BODY_TYPE"PLUMBING"
HDL_TAP"TRUE";
"B \NAC \NWC"12;
"S \NAC"
BN"19"31;
%"TAP"
"1","(-1100,3700)","2","standard","I79";
;
CDS_LIB"standard"
BODY_TYPE"PLUMBING"
HDL_TAP"TRUE";
"B \NAC \NWC"12;
"S \NAC"
BN"20"30;
%"TAP"
"1","(-1100,100)","2","standard","I8";
;
CDS_LIB"standard"
BODY_TYPE"PLUMBING"
HDL_TAP"TRUE";
"B \NAC \NWC"14;
"S \NAC"
BN"1"21;
%"TAP"
"1","(-1100,3750)","2","standard","I80";
;
CDS_LIB"standard"
BODY_TYPE"PLUMBING"
HDL_TAP"TRUE";
"B \NAC \NWC"12;
"S \NAC"
BN"21"29;
%"TAP"
"1","(-1100,3850)","2","standard","I81";
;
CDS_LIB"standard"
BODY_TYPE"PLUMBING"
HDL_TAP"TRUE";
"B \NAC \NWC"12;
"S \NAC"
BN"23"19;
%"TAP"
"1","(-1100,3800)","2","standard","I82";
;
CDS_LIB"standard"
BODY_TYPE"PLUMBING"
HDL_TAP"TRUE";
"B \NAC \NWC"12;
"S \NAC"
BN"22"20;
%"TAP"
"1","(-1100,3900)","2","standard","I83";
;
CDS_LIB"standard"
BODY_TYPE"PLUMBING"
HDL_TAP"TRUE";
"B \NAC \NWC"12;
"S \NAC"
BN"24"18;
%"TAP"
"1","(-1100,3950)","2","standard","I84";
;
CDS_LIB"standard"
BODY_TYPE"PLUMBING"
HDL_TAP"TRUE";
"B \NAC \NWC"12;
"S \NAC"
BN"25"17;
%"TAP"
"1","(-1100,4000)","2","standard","I85";
;
CDS_LIB"standard"
BODY_TYPE"PLUMBING"
HDL_TAP"TRUE";
"B \NAC \NWC"12;
"S \NAC"
BN"26"16;
%"TAP"
"1","(-1100,4050)","2","standard","I86";
;
CDS_LIB"standard"
BODY_TYPE"PLUMBING"
HDL_TAP"TRUE";
"B \NAC \NWC"12;
"S \NAC"
BN"27"15;
%"TAP"
"1","(-1100,4100)","2","standard","I87";
;
CDS_LIB"standard"
BODY_TYPE"PLUMBING"
HDL_TAP"TRUE";
"B \NAC \NWC"12;
"S \NAC"
BN"28"28;
%"TAP"
"1","(-1100,4250)","2","standard","I89";
;
CDS_LIB"standard"
BODY_TYPE"PLUMBING"
HDL_TAP"TRUE";
"B \NAC \NWC"12;
"S \NAC"
BN"31"25;
%"TAP"
"1","(-1100,300)","2","standard","I9";
;
CDS_LIB"standard"
BODY_TYPE"PLUMBING"
HDL_TAP"TRUE";
"B \NAC \NWC"9;
"S \NAC"
BN"0"98;
%"TAP"
"1","(-1100,4200)","2","standard","I90";
;
CDS_LIB"standard"
BODY_TYPE"PLUMBING"
HDL_TAP"TRUE";
"B \NAC \NWC"12;
"S \NAC"
BN"30"26;
%"TAP"
"1","(-1100,4150)","2","standard","I91";
;
CDS_LIB"standard"
BODY_TYPE"PLUMBING"
HDL_TAP"TRUE";
"B \NAC \NWC"12;
"S \NAC"
BN"29"27;
%"TAP"
"1","(2325,550)","0","standard","I93";
;
CDS_LIB"standard"
BODY_TYPE"PLUMBING"
HDL_TAP"TRUE";
"B \NAC \NWC"6;
"S \NAC"
BN"1"121;
%"TAP"
"1","(2325,500)","0","standard","I94";
;
CDS_LIB"standard"
BODY_TYPE"PLUMBING"
HDL_TAP"TRUE";
"B \NAC \NWC"6;
"S \NAC"
BN"0"120;
%"TAP"
"1","(2325,650)","0","standard","I95";
;
CDS_LIB"standard"
BODY_TYPE"PLUMBING"
HDL_TAP"TRUE";
"B \NAC \NWC"6;
"S \NAC"
BN"3"123;
%"TAP"
"1","(2325,600)","0","standard","I96";
;
CDS_LIB"standard"
BODY_TYPE"PLUMBING"
HDL_TAP"TRUE";
"B \NAC \NWC"6;
"S \NAC"
BN"2"122;
%"TAP"
"1","(2325,800)","0","standard","I97";
;
CDS_LIB"standard"
BODY_TYPE"PLUMBING"
HDL_TAP"TRUE";
"B \NAC \NWC"2;
"S \NAC"
BN"0"152;
%"TAP"
"1","(2325,850)","0","standard","I98";
;
CDS_LIB"standard"
BODY_TYPE"PLUMBING"
HDL_TAP"TRUE";
"B \NAC \NWC"2;
"S \NAC"
BN"1"153;
%"TAP"
"1","(2325,900)","0","standard","I99";
;
CDS_LIB"standard"
BODY_TYPE"PLUMBING"
HDL_TAP"TRUE";
"B \NAC \NWC"2;
"S \NAC"
BN"2"154;
END.
